FILE_TYPE = CONNECTIVITY;
{Allegro Design Entry HDL 17.2-2016 S081 (4005846) 1/11/2022}
"PAGE_NUMBER" = 196;
0"NC";
END.
